# BASEBOARD_FAB2 (Tioga Pass) — schematic netlist excerpt (pin names and nets, part order shuffled) for the footprints in the layout excerpt that follows; sources: Cadence DE-HDL packaged netlist, KiCad conversion of Wiwynn_Tioga_Pass_MB.brd

R3D24  RES  240 1.0% CHIP  pkg 0402  page 90 : A = PVCCIO_CPU1 ; B = PU_CPU1_SOCKET_ID_0
RT44  RES  0 5.0% CHIP  pkg 0603  page 236 : A = VR_PVNN_PCH_PH1_BOOT ; B = VR_PVNN_PCH_PH1_BOOT_R
T1P29  TPAD-SE-2P-GP  pkg DISCRET-GA1  page 256 : \1\ = L12_40OHM_6INCH ; GND1 = GND

(kicad_pcb
	(version 20260206)
	(generator "pcbnew")
	(generator_version "10.0")
	(general
		(thickness 1.6)
		(legacy_teardrops no)
	)
	(paper "A4")
	(title_block
		(title "Wiwynn_Tioga_Pass_MB.brd")
		(comment 1 "Tioga Pass / footprints 1066-1068 of 4770")
	)
	(layers
		(0 "F.Cu" signal "TOP")
		(4 "In1.Cu" signal "L2GND")
		(6 "In2.Cu" signal "L3")
		(8 "In3.Cu" signal "L4GND")
		(10 "In4.Cu" signal "L5")
		(12 "In5.Cu" signal "L6GND")
		(14 "In6.Cu" signal "L7VCC")
		(16 "In7.Cu" signal "L8VCC")
		(18 "In8.Cu" signal "L9GND")
		(20 "In9.Cu" signal "L10")
		(22 "In10.Cu" signal "L11GND")
		(24 "In11.Cu" signal "L12")
		(26 "In12.Cu" signal "L13GND")
		(2 "B.Cu" signal "BOTTOM")
		(9 "F.Adhes" user "F.Adhesive")
		(11 "B.Adhes" user "B.Adhesive")
		(13 "F.Paste" user "Package Geometry/Pastemask Top")
		(15 "B.Paste" user "Package Geometry/Pastemask Bottom")
		(5 "F.SilkS" user "Ref Des/Silkscreen Top")
		(7 "B.SilkS" user "Ref Des/Silkscreen Bottom")
		(1 "F.Mask" user "Board Geometry/Soldermask Top")
		(3 "B.Mask" user "Board Geometry/Soldermask Bottom")
		(17 "Dwgs.User" user "User.Drawings")
		(19 "Cmts.User" user "User.Comments")
		(21 "Eco1.User" user "User.Eco1")
		(23 "Eco2.User" user "User.Eco2")
		(25 "Edge.Cuts" user "Board Geometry/Outline")
		(27 "Margin" user)
		(31 "F.CrtYd" user "Package Geometry/Place Bound Top")
		(29 "B.CrtYd" user "Package Geometry/Place Bound Bottom")
		(35 "F.Fab" user "Ref Des/Assembly Top")
		(33 "B.Fab" user "Ref Des/Assembly Bottom")
	)
	(footprint ""
		(layer "F.Cu")
		(at 378.587 -158.1404 -90)
		(property "Reference" "RT44"
			(at 1.01473 0.656336 180)
			(unlocked yes)
			(layer "F.SilkS")
			(effects
				(font
					(size 0.4064 0.254)
					(thickness 0.1524)
				)
			)
		)
		(property "Value" ""
			(at 0 0 270)
			(layer "F.Fab")
			(effects
				(font
					(size 1.27 1.27)
				)
			)
		)
		(duplicate_pad_numbers_are_jumpers no)
		(fp_poly
			(pts
				(xy -0.4953 -0.2032) (xy 0.4953 -0.2032) (xy 0.4953 1.6002) (xy -0.4953 1.6002)
			)
			(stroke
				(width 0)
				(type default)
			)
			(fill no)
			(layer "F.CrtYd")
		)
		(fp_line
			(start -0.4953 1.6002)
			(end -0.4953 -0.2032)
			(stroke
				(width 0.1)
				(type default)
			)
			(layer "F.Fab")
		)
		(fp_line
			(start 0.4953 1.6002)
			(end -0.4953 1.6002)
			(stroke
				(width 0.1)
				(type default)
			)
			(layer "F.Fab")
		)
		(fp_line
			(start -0.4953 -0.2032)
			(end 0.4953 -0.2032)
			(stroke
				(width 0.1)
				(type default)
			)
			(layer "F.Fab")
		)
		(fp_line
			(start 0.4953 -0.2032)
			(end 0.4953 1.6002)
			(stroke
				(width 0.1)
				(type default)
			)
			(layer "F.Fab")
		)
		(pad "1" smd rect
			(at 0 0 270)
			(size 0.762 0.889)
			(layers "F.Cu" "F.Mask" "F.Paste")
			(net "VR_PVNN_PCH_PH1_BOOT")
		)
		(pad "2" smd rect
			(at 0 1.397 270)
			(size 0.762 0.889)
			(layers "F.Cu" "F.Mask" "F.Paste")
			(net "VR_PVNN_PCH_PH1_BOOT_R")
		)
		(zone
			(layer "F.Cu")
			(hatch none 0.5)
			(connect_pads
				(clearance 0)
			)
			(min_thickness 0.25)
			(keepout
				(tracks not_allowed)
				(vias allowed)
				(pads allowed)
				(copperpour not_allowed)
				(footprints allowed)
			)
			(placement
				(enabled no)
				(sheetname "")
			)
			(fill
				(thermal_gap 0.5)
				(thermal_bridge_width 0.5)
				(island_removal_mode 0)
			)
			(polygon
				(pts
					(xy 377.6345 -158.5214) (xy 377.6345 -157.7594) (xy 378.1425 -157.7594) (xy 378.1425 -158.5214)
				)
			)
		)
		(zone
			(layer "F.Cu")
			(hatch none 0.5)
			(connect_pads
				(clearance 0)
			)
			(min_thickness 0.25)
			(keepout
				(tracks allowed)
				(vias not_allowed)
				(pads allowed)
				(copperpour not_allowed)
				(footprints allowed)
			)
			(placement
				(enabled no)
				(sheetname "")
			)
			(fill
				(thermal_gap 0.5)
				(thermal_bridge_width 0.5)
				(island_removal_mode 0)
			)
			(polygon
				(pts
					(xy 377.6345 -157.7594) (xy 378.1425 -157.7594) (xy 378.1425 -158.5214) (xy 377.6345 -158.5214)
				)
			)
		)
	)
	(footprint ""
		(layer "F.Cu")
		(at 29.337 10.7315 -90)
		(property "Reference" "T1P29"
			(at 0 0 270)
			(layer "F.SilkS")
			(hide yes)
			(effects
				(font
					(size 1.27 1.27)
				)
			)
		)
		(property "Value" "*"
			(at 0 -3.44805 270)
			(unlocked yes)
			(layer "F.Fab")
			(hide yes)
			(effects
				(font
					(size 0.889 0.889)
					(thickness 0.1524)
				)
			)
		)
		(property "Device Type" "TPAD-SE-2P-GP_DISCRET-GA1-TPADA"
			(at 0 -4.97205 270)
			(unlocked yes)
			(layer "F.Fab")
			(hide yes)
			(effects
				(font
					(size 0.889 0.889)
					(thickness 0.1524)
				)
			)
		)
		(duplicate_pad_numbers_are_jumpers no)
		(fp_line
			(start -1.016 2.286)
			(end -1.016 -2.286)
			(stroke
				(width 0.1524)
				(type default)
			)
			(layer "F.SilkS")
		)
		(fp_line
			(start 1.016 2.286)
			(end -1.016 2.286)
			(stroke
				(width 0.1524)
				(type default)
			)
			(layer "F.SilkS")
		)
		(fp_line
			(start -1.016 -2.286)
			(end 1.016 -2.286)
			(stroke
				(width 0.1524)
				(type default)
			)
			(layer "F.SilkS")
		)
		(fp_line
			(start 1.016 -2.286)
			(end 1.016 2.286)
			(stroke
				(width 0.1524)
				(type default)
			)
			(layer "F.SilkS")
		)
		(fp_rect
			(start -1.27 2.54)
			(end 1.27 -2.54)
			(stroke
				(width 0)
				(type default)
			)
			(fill no)
			(layer "F.CrtYd")
		)
		(fp_rect
			(start -1.27 2.54)
			(end 1.27 -2.54)
			(stroke
				(width 0)
				(type default)
			)
			(fill no)
			(layer "F.Fab")
		)
		(pad "1" thru_hole circle
			(at 0 -1.27 270)
			(size 1.524 1.524)
			(drill 0.9144)
			(layers "*.Cu" "*.Mask")
			(remove_unused_layers no)
			(net "L12_40OHM_6INCH")
			(clearance -0.0508)
			(thermal_gap 0.127)
			(padstack
				(mode front_inner_back)
				(layer "Inner"
					(shape circle)
					(size 1.1684 1.1684)
					(clearance 0.127)
				)
				(layer "B.Cu"
					(shape circle)
					(size 1.524 1.524)
					(clearance -0.0508)
				)
			)
		)
		(pad "GND1" thru_hole rect
			(at 0 1.27 270)
			(size 1.524 1.524)
			(drill 0.9144)
			(layers "*.Cu" "*.Mask")
			(remove_unused_layers no)
			(net "GND")
			(clearance -0.0508)
			(thermal_gap 0.127)
			(padstack
				(mode front_inner_back)
				(layer "Inner"
					(shape circle)
					(size 1.1684 1.1684)
					(clearance 0.127)
				)
				(layer "B.Cu"
					(shape rect)
					(size 1.524 1.524)
					(clearance -0.0508)
				)
			)
		)
	)
	(footprint ""
		(layer "F.Cu")
		(at 111.633 -69.85)
		(property "Reference" "R3D24"
			(at 0 0 0)
			(layer "F.SilkS")
			(hide yes)
			(effects
				(font
					(size 1.27 1.27)
				)
			)
		)
		(property "Value" ""
			(at 0 0 0)
			(layer "F.Fab")
			(effects
				(font
					(size 1.27 1.27)
				)
			)
		)
		(duplicate_pad_numbers_are_jumpers no)
		(fp_poly
			(pts
				(xy -0.2794 -0.1016) (xy 0.2794 -0.1016) (xy 0.2794 0.9906) (xy -0.2794 0.9906)
			)
			(stroke
				(width 0)
				(type default)
			)
			(fill no)
			(layer "F.CrtYd")
		)
		(fp_line
			(start -0.2794 -0.1016)
			(end -0.2794 0.9906)
			(stroke
				(width 0.1)
				(type default)
			)
			(layer "F.Fab")
		)
		(fp_line
			(start -0.2794 0.9906)
			(end 0.2794 0.9906)
			(stroke
				(width 0.1)
				(type default)
			)
			(layer "F.Fab")
		)
		(fp_line
			(start 0.2794 -0.1016)
			(end -0.2794 -0.1016)
			(stroke
				(width 0.1)
				(type default)
			)
			(layer "F.Fab")
		)
		(fp_line
			(start 0.2794 0.9906)
			(end 0.2794 -0.1016)
			(stroke
				(width 0.1)
				(type default)
			)
			(layer "F.Fab")
		)
		(pad "1" smd rect
			(at 0 0)
			(size 0.508 0.508)
			(layers "F.Cu" "F.Mask" "F.Paste")
			(net "PVCCIO_CPU1")
		)
		(pad "2" smd rect
			(at 0 0.889)
			(size 0.508 0.508)
			(layers "F.Cu" "F.Mask" "F.Paste")
			(net "PU_CPU1_SOCKET_ID_0")
		)
		(zone
			(layer "F.Cu")
			(hatch none 0.5)
			(connect_pads
				(clearance 0)
			)
			(min_thickness 0.25)
			(keepout
				(tracks allowed)
				(vias not_allowed)
				(pads allowed)
				(copperpour not_allowed)
				(footprints allowed)
			)
			(placement
				(enabled no)
				(sheetname "")
			)
			(fill
				(thermal_gap 0.5)
				(thermal_bridge_width 0.5)
				(island_removal_mode 0)
			)
			(polygon
				(pts
					(xy 111.379 -69.596) (xy 111.887 -69.596) (xy 111.887 -69.215) (xy 111.379 -69.215)
				)
			)
		)
		(zone
			(layer "F.Cu")
			(hatch none 0.5)
			(connect_pads
				(clearance 0)
			)
			(min_thickness 0.25)
			(keepout
				(tracks not_allowed)
				(vias allowed)
				(pads allowed)
				(copperpour not_allowed)
				(footprints allowed)
			)
			(placement
				(enabled no)
				(sheetname "")
			)
			(fill
				(thermal_gap 0.5)
				(thermal_bridge_width 0.5)
				(island_removal_mode 0)
			)
			(polygon
				(pts
					(xy 111.379 -69.215) (xy 111.887 -69.215) (xy 111.887 -69.596) (xy 111.379 -69.596)
				)
			)
		)
	)
)
